# S9S_MB_2U (Grand Teton) — schematic netlist excerpt (pin names and nets, part order shuffled) for the footprints in the layout excerpt that follows; sources: Cadence DE-HDL packaged netlist, KiCad conversion of 03242023_DA0F0TMBIJ0_F0T_Motherboard_J_brd_V01_OCP.brd

PR2527  Q_RES  10 1% EMPTY  pkg 0402LF  page 304 : A = P12V_HSC_SENSE2_N ; B = P12V_HSC_SENSE2_R4_N
R2509  Q_RES  1K 1% EMPTY  pkg 0402LF  page 184 : A = FM_M2_SSD0_E7_PEDET ; B = GND
C362  Q_CAP  47UF 4V 20% X6S  pkg C0805  page 75 : A = PVCCIN_CPU0 ; B = GND

(kicad_pcb
	(version 20260206)
	(generator "pcbnew")
	(generator_version "10.0")
	(general
		(thickness 1.6)
		(legacy_teardrops no)
	)
	(paper "A4")
	(title_block
		(title "03242023_DA0F0TMBIJ0_F0T_Motherboard_J_brd_V01_OCP.brd")
		(comment 1 "Grand Teton / footprints 4984-4986 of 6105")
	)
	(layers
		(0 "F.Cu" signal "TOP")
		(4 "In1.Cu" signal "GND")
		(6 "In2.Cu" signal "IN1")
		(8 "In3.Cu" signal "GND1")
		(10 "In4.Cu" signal "IN2")
		(12 "In5.Cu" signal "GND2")
		(14 "In6.Cu" signal "IN3")
		(16 "In7.Cu" signal "GND3")
		(18 "In8.Cu" signal "VCC")
		(20 "In9.Cu" signal "VCC1")
		(22 "In10.Cu" signal "GND4")
		(24 "In11.Cu" signal "IN4")
		(26 "In12.Cu" signal "GND5")
		(28 "In13.Cu" signal "IN5")
		(30 "In14.Cu" signal "GND6")
		(32 "In15.Cu" signal "IN6")
		(34 "In16.Cu" signal "GND7")
		(2 "B.Cu" signal "BOTTOM")
		(9 "F.Adhes" user "F.Adhesive")
		(11 "B.Adhes" user "B.Adhesive")
		(13 "F.Paste" user "Package Geometry/Pastemask Top")
		(15 "B.Paste" user "Package Geometry/Pastemask Bottom")
		(5 "F.SilkS" user "Ref Des/Silkscreen Top")
		(7 "B.SilkS" user "Ref Des/Silkscreen Bottom")
		(1 "F.Mask" user "Board Geometry/Soldermask Top")
		(3 "B.Mask" user "Board Geometry/Soldermask Bottom")
		(17 "Dwgs.User" user "User.Drawings")
		(19 "Cmts.User" user "User.Comments")
		(21 "Eco1.User" user "User.Eco1")
		(23 "Eco2.User" user "User.Eco2")
		(25 "Edge.Cuts" user "Board Geometry/Outline")
		(27 "Margin" user)
		(31 "F.CrtYd" user "Package Geometry/Place Bound Top")
		(29 "B.CrtYd" user "Package Geometry/Place Bound Bottom")
		(35 "F.Fab" user "Ref Des/Assembly Top")
		(33 "B.Fab" user "Ref Des/Assembly Bottom")
	)
	(footprint ""
		(layer "B.Cu")
		(at 369.49888 -43.144948 180)
		(property "Reference" "R2509"
			(at 0 0 0)
			(layer "B.SilkS")
			(hide yes)
			(effects
				(font
					(size 1.27 1.27)
				)
				(justify mirror)
			)
		)
		(property "Value" ""
			(at 0 0 0)
			(layer "B.Fab")
			(effects
				(font
					(size 1.27 1.27)
				)
				(justify mirror)
			)
		)
		(duplicate_pad_numbers_are_jumpers no)
		(fp_line
			(start 0.7874 0.4064)
			(end 0.7874 -0.4064)
			(stroke
				(width 0.1524)
				(type default)
			)
			(layer "B.SilkS")
		)
		(fp_line
			(start 0.7874 -0.4064)
			(end -0.7874 -0.4064)
			(stroke
				(width 0.1524)
				(type default)
			)
			(layer "B.SilkS")
		)
		(fp_line
			(start -0.7874 0.4064)
			(end 0.7874 0.4064)
			(stroke
				(width 0.1524)
				(type default)
			)
			(layer "B.SilkS")
		)
		(fp_line
			(start -0.7874 -0.4064)
			(end -0.7874 0.4064)
			(stroke
				(width 0.1524)
				(type default)
			)
			(layer "B.SilkS")
		)
		(fp_line
			(start 0.67945 0.3048)
			(end 0.67945 -0.305054)
			(stroke
				(width 0.1)
				(type default)
			)
			(layer "B.Fab")
		)
		(fp_line
			(start 0.67945 -0.305054)
			(end 0.12065 -0.305054)
			(stroke
				(width 0.1)
				(type default)
			)
			(layer "B.Fab")
		)
		(fp_line
			(start 0.12065 0.3048)
			(end 0.67945 0.3048)
			(stroke
				(width 0.1)
				(type default)
			)
			(layer "B.Fab")
		)
		(fp_line
			(start 0.12065 0.2794)
			(end 0.12065 0.3048)
			(stroke
				(width 0.1)
				(type default)
			)
			(layer "B.Fab")
		)
		(fp_line
			(start 0.12065 -0.2794)
			(end -0.12065 -0.2794)
			(stroke
				(width 0.1)
				(type default)
			)
			(layer "B.Fab")
		)
		(fp_line
			(start 0.12065 -0.305054)
			(end 0.12065 -0.2794)
			(stroke
				(width 0.1)
				(type default)
			)
			(layer "B.Fab")
		)
		(fp_line
			(start -0.120396 0.3048)
			(end -0.120396 0.2794)
			(stroke
				(width 0.1)
				(type default)
			)
			(layer "B.Fab")
		)
		(fp_line
			(start -0.120396 0.2794)
			(end 0.12065 0.2794)
			(stroke
				(width 0.1)
				(type default)
			)
			(layer "B.Fab")
		)
		(fp_line
			(start -0.12065 -0.2794)
			(end -0.12065 -0.3048)
			(stroke
				(width 0.1)
				(type default)
			)
			(layer "B.Fab")
		)
		(fp_line
			(start -0.12065 -0.3048)
			(end -0.67945 -0.3048)
			(stroke
				(width 0.1)
				(type default)
			)
			(layer "B.Fab")
		)
		(fp_line
			(start -0.67945 0.3048)
			(end -0.120396 0.3048)
			(stroke
				(width 0.1)
				(type default)
			)
			(layer "B.Fab")
		)
		(fp_line
			(start -0.67945 -0.3048)
			(end -0.67945 0.3048)
			(stroke
				(width 0.1)
				(type default)
			)
			(layer "B.Fab")
		)
		(pad "1" smd circle
			(at 0.40005 0)
			(size 0 0)
			(layers "B.Cu" "B.Mask" "B.Paste")
			(net "FM_M2_SSD0_E7_PEDET")
		)
		(pad "2" smd circle
			(at -0.40005 0)
			(size 0 0)
			(layers "B.Cu" "B.Mask" "B.Paste")
			(net "GND")
		)
	)
	(footprint ""
		(layer "B.Cu")
		(at 292.528498 -400.999452 -90)
		(property "Reference" "PR2527"
			(at 0 0 90)
			(layer "B.SilkS")
			(hide yes)
			(effects
				(font
					(size 1.27 1.27)
				)
				(justify mirror)
			)
		)
		(property "Value" ""
			(at 0 0 90)
			(layer "B.Fab")
			(effects
				(font
					(size 1.27 1.27)
				)
				(justify mirror)
			)
		)
		(duplicate_pad_numbers_are_jumpers no)
		(fp_line
			(start -0.7874 0.4064)
			(end 0.7874 0.4064)
			(stroke
				(width 0.1524)
				(type default)
			)
			(layer "B.SilkS")
		)
		(fp_line
			(start 0.7874 0.4064)
			(end 0.7874 -0.4064)
			(stroke
				(width 0.1524)
				(type default)
			)
			(layer "B.SilkS")
		)
		(fp_line
			(start -0.7874 -0.4064)
			(end -0.7874 0.4064)
			(stroke
				(width 0.1524)
				(type default)
			)
			(layer "B.SilkS")
		)
		(fp_line
			(start 0.7874 -0.4064)
			(end -0.7874 -0.4064)
			(stroke
				(width 0.1524)
				(type default)
			)
			(layer "B.SilkS")
		)
		(fp_line
			(start -0.67945 0.3048)
			(end -0.120396 0.3048)
			(stroke
				(width 0.1)
				(type default)
			)
			(layer "B.Fab")
		)
		(fp_line
			(start -0.120396 0.3048)
			(end -0.120396 0.2794)
			(stroke
				(width 0.1)
				(type default)
			)
			(layer "B.Fab")
		)
		(fp_line
			(start 0.12065 0.3048)
			(end 0.67945 0.3048)
			(stroke
				(width 0.1)
				(type default)
			)
			(layer "B.Fab")
		)
		(fp_line
			(start 0.67945 0.3048)
			(end 0.67945 -0.305054)
			(stroke
				(width 0.1)
				(type default)
			)
			(layer "B.Fab")
		)
		(fp_line
			(start -0.120396 0.2794)
			(end 0.12065 0.2794)
			(stroke
				(width 0.1)
				(type default)
			)
			(layer "B.Fab")
		)
		(fp_line
			(start 0.12065 0.2794)
			(end 0.12065 0.3048)
			(stroke
				(width 0.1)
				(type default)
			)
			(layer "B.Fab")
		)
		(fp_line
			(start -0.12065 -0.2794)
			(end -0.12065 -0.3048)
			(stroke
				(width 0.1)
				(type default)
			)
			(layer "B.Fab")
		)
		(fp_line
			(start 0.12065 -0.2794)
			(end -0.12065 -0.2794)
			(stroke
				(width 0.1)
				(type default)
			)
			(layer "B.Fab")
		)
		(fp_line
			(start -0.67945 -0.3048)
			(end -0.67945 0.3048)
			(stroke
				(width 0.1)
				(type default)
			)
			(layer "B.Fab")
		)
		(fp_line
			(start -0.12065 -0.3048)
			(end -0.67945 -0.3048)
			(stroke
				(width 0.1)
				(type default)
			)
			(layer "B.Fab")
		)
		(fp_line
			(start 0.12065 -0.305054)
			(end 0.12065 -0.2794)
			(stroke
				(width 0.1)
				(type default)
			)
			(layer "B.Fab")
		)
		(fp_line
			(start 0.67945 -0.305054)
			(end 0.12065 -0.305054)
			(stroke
				(width 0.1)
				(type default)
			)
			(layer "B.Fab")
		)
		(pad "1" smd circle
			(at 0.40005 0 90)
			(size 0 0)
			(layers "B.Cu" "B.Mask" "B.Paste")
			(net "P12V_HSC_SENSE2_N")
		)
		(pad "2" smd circle
			(at -0.40005 0 90)
			(size 0 0)
			(layers "B.Cu" "B.Mask" "B.Paste")
			(net "P12V_HSC_SENSE2_R4_N")
		)
	)
	(footprint ""
		(layer "B.Cu")
		(at 355.397308 -255.853946 -90)
		(property "Reference" "C362"
			(at 0 0 90)
			(layer "B.SilkS")
			(hide yes)
			(effects
				(font
					(size 1.27 1.27)
				)
				(justify mirror)
			)
		)
		(property "Value" ""
			(at 0 0 90)
			(layer "B.Fab")
			(effects
				(font
					(size 1.27 1.27)
				)
				(justify mirror)
			)
		)
		(duplicate_pad_numbers_are_jumpers no)
		(fp_line
			(start -1.524 0.762)
			(end 1.524 0.762)
			(stroke
				(width 0.1524)
				(type default)
			)
			(layer "B.SilkS")
		)
		(fp_line
			(start 1.524 0.762)
			(end 1.524 -0.762)
			(stroke
				(width 0.1524)
				(type default)
			)
			(layer "B.SilkS")
		)
		(fp_line
			(start -1.524 -0.762)
			(end -1.524 0.762)
			(stroke
				(width 0.1524)
				(type default)
			)
			(layer "B.SilkS")
		)
		(fp_line
			(start 1.524 -0.762)
			(end -1.524 -0.762)
			(stroke
				(width 0.1524)
				(type default)
			)
			(layer "B.SilkS")
		)
		(fp_line
			(start -1.1049 0.724916)
			(end -1.1049 -0.724916)
			(stroke
				(width 0.1)
				(type default)
			)
			(layer "B.Fab")
		)
		(fp_line
			(start 1.1049 0.724916)
			(end -1.1049 0.724916)
			(stroke
				(width 0.1)
				(type default)
			)
			(layer "B.Fab")
		)
		(fp_line
			(start -1.1049 -0.724916)
			(end 1.1049 -0.724916)
			(stroke
				(width 0.1)
				(type default)
			)
			(layer "B.Fab")
		)
		(fp_line
			(start 1.1049 -0.724916)
			(end 1.1049 0.724916)
			(stroke
				(width 0.1)
				(type default)
			)
			(layer "B.Fab")
		)
		(pad "1" smd rect
			(at 0.889 0 270)
			(size 1.016 1.27)
			(layers "B.Cu" "B.Mask" "B.Paste")
			(net "PVCCIN_CPU0")
		)
		(pad "2" smd rect
			(at -0.889 0 270)
			(size 1.016 1.27)
			(layers "B.Cu" "B.Mask" "B.Paste")
			(net "GND")
		)
	)
)
